# S9S_MB_2U (Grand Teton) — schematic netlist excerpt (pin names and nets, part order shuffled) for the footprints in the layout excerpt that follows; sources: Cadence DE-HDL packaged netlist, KiCad conversion of 03242023_DA0F0TMBIJ0_F0T_Motherboard_J_brd_V01_OCP.brd

C735  Q_CAP_DIFFBUS  DIFF BUS_0.22UF 6.3V 20% X6S  pkg C0201  page 176 : \1\ = P5E_CPU1_PE0_TX_C_DP<3> ; \2\ = P5E_CPU1_PE0_TX_DP<3>
C2175  Q_CAP  100PF 50V 5% EMPTY  pkg 0402  page 250 : A = P12V_OCP_V3_2_ISENSE_MAM ; B = GND
R241  Q_RES  4.75K 1% CHIP  pkg 0402LF  page 121 : A = P3V3 ; B = H_CPU0_THERMTRIP_VT_N

(kicad_pcb
	(version 20260206)
	(generator "pcbnew")
	(generator_version "10.0")
	(general
		(thickness 1.6)
		(legacy_teardrops no)
	)
	(paper "A4")
	(title_block
		(title "03242023_DA0F0TMBIJ0_F0T_Motherboard_J_brd_V01_OCP.brd")
		(comment 1 "Grand Teton / footprints 1865-1867 of 6105")
	)
	(layers
		(0 "F.Cu" signal "TOP")
		(4 "In1.Cu" signal "GND")
		(6 "In2.Cu" signal "IN1")
		(8 "In3.Cu" signal "GND1")
		(10 "In4.Cu" signal "IN2")
		(12 "In5.Cu" signal "GND2")
		(14 "In6.Cu" signal "IN3")
		(16 "In7.Cu" signal "GND3")
		(18 "In8.Cu" signal "VCC")
		(20 "In9.Cu" signal "VCC1")
		(22 "In10.Cu" signal "GND4")
		(24 "In11.Cu" signal "IN4")
		(26 "In12.Cu" signal "GND5")
		(28 "In13.Cu" signal "IN5")
		(30 "In14.Cu" signal "GND6")
		(32 "In15.Cu" signal "IN6")
		(34 "In16.Cu" signal "GND7")
		(2 "B.Cu" signal "BOTTOM")
		(9 "F.Adhes" user "F.Adhesive")
		(11 "B.Adhes" user "B.Adhesive")
		(13 "F.Paste" user "Package Geometry/Pastemask Top")
		(15 "B.Paste" user "Package Geometry/Pastemask Bottom")
		(5 "F.SilkS" user "Ref Des/Silkscreen Top")
		(7 "B.SilkS" user "Ref Des/Silkscreen Bottom")
		(1 "F.Mask" user "Board Geometry/Soldermask Top")
		(3 "B.Mask" user "Board Geometry/Soldermask Bottom")
		(17 "Dwgs.User" user "User.Drawings")
		(19 "Cmts.User" user "User.Comments")
		(21 "Eco1.User" user "User.Eco1")
		(23 "Eco2.User" user "User.Eco2")
		(25 "Edge.Cuts" user "Board Geometry/Outline")
		(27 "Margin" user)
		(31 "F.CrtYd" user "Package Geometry/Place Bound Top")
		(29 "B.CrtYd" user "Package Geometry/Place Bound Bottom")
		(35 "F.Fab" user "Ref Des/Assembly Top")
		(33 "B.Fab" user "Ref Des/Assembly Bottom")
	)
	(footprint ""
		(layer "F.Cu")
		(at 32.761428 -98.570034 180)
		(property "Reference" "C2175"
			(at 0 0 180)
			(layer "F.SilkS")
			(hide yes)
			(effects
				(font
					(size 1.27 1.27)
				)
			)
		)
		(property "Value" ""
			(at 0 0 180)
			(layer "F.Fab")
			(effects
				(font
					(size 1.27 1.27)
				)
			)
		)
		(duplicate_pad_numbers_are_jumpers no)
		(fp_line
			(start 0.7874 0.4064)
			(end -0.7874 0.4064)
			(stroke
				(width 0.1524)
				(type default)
			)
			(layer "F.SilkS")
		)
		(fp_line
			(start 0.7874 -0.4064)
			(end 0.7874 0.4064)
			(stroke
				(width 0.1524)
				(type default)
			)
			(layer "F.SilkS")
		)
		(fp_line
			(start -0.7874 0.4064)
			(end -0.7874 -0.4064)
			(stroke
				(width 0.1524)
				(type default)
			)
			(layer "F.SilkS")
		)
		(fp_line
			(start -0.7874 -0.4064)
			(end 0.7874 -0.4064)
			(stroke
				(width 0.1524)
				(type default)
			)
			(layer "F.SilkS")
		)
		(fp_line
			(start 0.67945 0.3048)
			(end 0.120396 0.3048)
			(stroke
				(width 0.1)
				(type default)
			)
			(layer "F.Fab")
		)
		(fp_line
			(start 0.67945 -0.3048)
			(end 0.67945 0.3048)
			(stroke
				(width 0.1)
				(type default)
			)
			(layer "F.Fab")
		)
		(fp_line
			(start 0.12065 -0.2794)
			(end 0.12065 -0.3048)
			(stroke
				(width 0.1)
				(type default)
			)
			(layer "F.Fab")
		)
		(fp_line
			(start 0.12065 -0.3048)
			(end 0.67945 -0.3048)
			(stroke
				(width 0.1)
				(type default)
			)
			(layer "F.Fab")
		)
		(fp_line
			(start 0.120396 0.3048)
			(end 0.120396 0.2794)
			(stroke
				(width 0.1)
				(type default)
			)
			(layer "F.Fab")
		)
		(fp_line
			(start 0.120396 0.2794)
			(end -0.12065 0.2794)
			(stroke
				(width 0.1)
				(type default)
			)
			(layer "F.Fab")
		)
		(fp_line
			(start -0.12065 0.3048)
			(end -0.67945 0.3048)
			(stroke
				(width 0.1)
				(type default)
			)
			(layer "F.Fab")
		)
		(fp_line
			(start -0.12065 0.2794)
			(end -0.12065 0.3048)
			(stroke
				(width 0.1)
				(type default)
			)
			(layer "F.Fab")
		)
		(fp_line
			(start -0.12065 -0.2794)
			(end 0.12065 -0.2794)
			(stroke
				(width 0.1)
				(type default)
			)
			(layer "F.Fab")
		)
		(fp_line
			(start -0.12065 -0.305054)
			(end -0.12065 -0.2794)
			(stroke
				(width 0.1)
				(type default)
			)
			(layer "F.Fab")
		)
		(fp_line
			(start -0.67945 0.3048)
			(end -0.67945 -0.305054)
			(stroke
				(width 0.1)
				(type default)
			)
			(layer "F.Fab")
		)
		(fp_line
			(start -0.67945 -0.305054)
			(end -0.12065 -0.305054)
			(stroke
				(width 0.1)
				(type default)
			)
			(layer "F.Fab")
		)
		(pad "1" smd circle
			(at -0.40005 0 180)
			(size 0 0)
			(layers "F.Cu" "F.Mask" "F.Paste")
			(net "P12V_OCP_V3_2_ISENSE_MAM")
		)
		(pad "2" smd circle
			(at 0.40005 0 180)
			(size 0 0)
			(layers "F.Cu" "F.Mask" "F.Paste")
			(net "GND")
		)
	)
	(footprint ""
		(layer "F.Cu")
		(at 85.627718 -402.371052 -90)
		(property "Reference" "C735"
			(at 0 0 270)
			(layer "F.SilkS")
			(hide yes)
			(effects
				(font
					(size 1.27 1.27)
				)
			)
		)
		(property "Value" ""
			(at 0 0 270)
			(layer "F.Fab")
			(effects
				(font
					(size 1.27 1.27)
				)
			)
		)
		(duplicate_pad_numbers_are_jumpers no)
		(fp_line
			(start -0.299974 0.150114)
			(end -0.299974 -0.150114)
			(stroke
				(width 0.1)
				(type default)
			)
			(layer "F.Fab")
		)
		(fp_line
			(start 0.299974 0.150114)
			(end -0.299974 0.150114)
			(stroke
				(width 0.1)
				(type default)
			)
			(layer "F.Fab")
		)
		(fp_line
			(start -0.299974 -0.150114)
			(end 0.299974 -0.150114)
			(stroke
				(width 0.1)
				(type default)
			)
			(layer "F.Fab")
		)
		(fp_line
			(start 0.299974 -0.150114)
			(end 0.299974 0.150114)
			(stroke
				(width 0.1)
				(type default)
			)
			(layer "F.Fab")
		)
		(pad "1" smd rect
			(at -0.2667 0 270)
			(size 0.3048 0.381)
			(layers "F.Cu" "F.Mask" "F.Paste")
			(net "P5E_CPU1_PE0_TX_C_DP<3>")
		)
		(pad "2" smd rect
			(at 0.2667 0 270)
			(size 0.3048 0.381)
			(layers "F.Cu" "F.Mask" "F.Paste")
			(net "P5E_CPU1_PE0_TX_DP<3>")
		)
	)
	(footprint ""
		(layer "F.Cu")
		(at 122.61088 -92.674948 90)
		(property "Reference" "R241"
			(at 0 0 90)
			(layer "F.SilkS")
			(hide yes)
			(effects
				(font
					(size 1.27 1.27)
				)
			)
		)
		(property "Value" ""
			(at 0 0 90)
			(layer "F.Fab")
			(effects
				(font
					(size 1.27 1.27)
				)
			)
		)
		(duplicate_pad_numbers_are_jumpers no)
		(fp_line
			(start 0.7874 -0.4064)
			(end 0.7874 0.4064)
			(stroke
				(width 0.1524)
				(type default)
			)
			(layer "F.SilkS")
		)
		(fp_line
			(start -0.7874 -0.4064)
			(end 0.7874 -0.4064)
			(stroke
				(width 0.1524)
				(type default)
			)
			(layer "F.SilkS")
		)
		(fp_line
			(start 0.7874 0.4064)
			(end -0.7874 0.4064)
			(stroke
				(width 0.1524)
				(type default)
			)
			(layer "F.SilkS")
		)
		(fp_line
			(start -0.7874 0.4064)
			(end -0.7874 -0.4064)
			(stroke
				(width 0.1524)
				(type default)
			)
			(layer "F.SilkS")
		)
		(fp_line
			(start -0.12065 -0.305054)
			(end -0.12065 -0.2794)
			(stroke
				(width 0.1)
				(type default)
			)
			(layer "F.Fab")
		)
		(fp_line
			(start -0.67945 -0.305054)
			(end -0.12065 -0.305054)
			(stroke
				(width 0.1)
				(type default)
			)
			(layer "F.Fab")
		)
		(fp_line
			(start 0.67945 -0.3048)
			(end 0.67945 0.3048)
			(stroke
				(width 0.1)
				(type default)
			)
			(layer "F.Fab")
		)
		(fp_line
			(start 0.12065 -0.3048)
			(end 0.67945 -0.3048)
			(stroke
				(width 0.1)
				(type default)
			)
			(layer "F.Fab")
		)
		(fp_line
			(start 0.12065 -0.2794)
			(end 0.12065 -0.3048)
			(stroke
				(width 0.1)
				(type default)
			)
			(layer "F.Fab")
		)
		(fp_line
			(start -0.12065 -0.2794)
			(end 0.12065 -0.2794)
			(stroke
				(width 0.1)
				(type default)
			)
			(layer "F.Fab")
		)
		(fp_line
			(start 0.120396 0.2794)
			(end -0.12065 0.2794)
			(stroke
				(width 0.1)
				(type default)
			)
			(layer "F.Fab")
		)
		(fp_line
			(start -0.12065 0.2794)
			(end -0.12065 0.3048)
			(stroke
				(width 0.1)
				(type default)
			)
			(layer "F.Fab")
		)
		(fp_line
			(start 0.67945 0.3048)
			(end 0.120396 0.3048)
			(stroke
				(width 0.1)
				(type default)
			)
			(layer "F.Fab")
		)
		(fp_line
			(start 0.120396 0.3048)
			(end 0.120396 0.2794)
			(stroke
				(width 0.1)
				(type default)
			)
			(layer "F.Fab")
		)
		(fp_line
			(start -0.12065 0.3048)
			(end -0.67945 0.3048)
			(stroke
				(width 0.1)
				(type default)
			)
			(layer "F.Fab")
		)
		(fp_line
			(start -0.67945 0.3048)
			(end -0.67945 -0.305054)
			(stroke
				(width 0.1)
				(type default)
			)
			(layer "F.Fab")
		)
		(pad "1" smd circle
			(at -0.40005 0 90)
			(size 0 0)
			(layers "F.Cu" "F.Mask" "F.Paste")
			(net "P3V3")
		)
		(pad "2" smd circle
			(at 0.40005 0 90)
			(size 0 0)
			(layers "F.Cu" "F.Mask" "F.Paste")
			(net "H_CPU0_THERMTRIP_VT_N")
		)
	)
)
